G04 ================== begin FILE IDENTIFICATION RECORD ==================*
G04 Layout Name:  17301-sa.brd*
G04 Film Name:    P_OUTLINE*
G04 File Format:  Gerber RS274X*
G04 File Origin:  Cadence Allegro 16.6-2015-S079*
G04 Origin Date:  Thu Jun 22 17:49:43 2017*
G04 *
G04 Layer:  BOARD GEOMETRY/PANEL_OUTLINE*
G04 *
G04 Offset:    (0.00 0.00)*
G04 Mirror:    No*
G04 Mode:      Positive*
G04 Rotation:  0*
G04 FullContactRelief:  No*
G04 UndefLineWidth:     6.00*
G04 ================== end FILE IDENTIFICATION RECORD ====================*
%FSLAX35Y35*MOIN*%
%IR0*IPPOS*OFA0.00000B0.00000*MIA0B0*SFA1.00000B1.00000*%
%ADD10C,.006*%
G75*
%LPD*%
G75*
G54D10*
G01X-25590Y9843D02*
G03X-15748Y0I9842J-1D01*
G01X-25590Y89370D02*
Y9843D01*
G01X-23622Y91339D02*
G03X-25590Y89370I1J-1969D01*
G01X-7874Y91339D02*
X-23622D01*
G01X-25590Y109055D02*
G03X-21653Y105118I3937J0D01*
G01X-25590Y357874D02*
Y109055D01*
G01X-21653Y105118D02*
X261811D01*
G01X-25590Y371654D02*
G03X-23622Y369685I1968J-1D01*
G01X-21653Y361811D02*
G03X-25590Y357874I0J-3937D01*
G01X1969Y361811D02*
X-21653D01*
G01X-7874Y369685D02*
X-23622D01*
G01X-25590Y459055D02*
Y371654D01*
G01X-23622Y461024D02*
G03X-25590Y459055I1J-1969D01*
G01X-7874Y461024D02*
X-23622D01*
G01X-25590Y478740D02*
G03X-21653Y474803I3937J0D01*
G01X-25590Y727559D02*
Y478740D01*
G01X-21653Y474803D02*
X261811D01*
G01X-21653Y731496D02*
G03X-25590Y727559I0J-3937D01*
G01X1969Y731496D02*
X-21653D01*
G01X-11811Y0D02*
G03X-7874Y3937I0J3937D01*
G01X-11811Y0D02*
X-15748D01*
G01X0Y3937D02*
G03X3937Y0I3937J0D01*
G01X-7874Y33071D02*
Y3937D01*
G01X0Y87402D02*
Y3937D01*
G01Y33071D02*
G03X-7874I-3937J0D01*
G01Y58268D02*
G03X0I3937J0D01*
G01X-7874Y91339D02*
Y58268D01*
G01X3937Y91339D02*
G03X0Y87402I0J-3937D01*
G01X5906Y357874D02*
G03X1969Y361811I-3937J0D01*
G01X0Y373622D02*
G03X3937Y369685I3937J0D01*
G01X-7874Y402756D02*
Y369685D01*
G01X0Y457087D02*
Y373622D01*
G01Y402756D02*
G03X-7874I-3937J0D01*
G01Y427953D02*
G03X0I3937J0D01*
G01X-7874Y461024D02*
Y427953D01*
G01X3937Y461024D02*
G03X0Y457087I0J-3937D01*
G01X5906Y727559D02*
G03X1969Y731496I-3937J0D01*
G01X3937Y0D02*
X372048D01*
G01X192914Y91339D02*
X3937D01*
G01X5906Y290748D02*
G03X9843Y286811I3937J0D01*
G01X5906Y357874D02*
Y290748D01*
G01X69488Y286811D02*
X9843D01*
G01X13780Y315650D02*
Y294685D01*
G01X69488D02*
X13780D01*
G01Y315650D02*
G03X5906I-3937J0D01*
G01Y340847D02*
G03X13780I3937J0D01*
G01Y361811D02*
Y340847D01*
G01X3937Y369685D02*
X372048D01*
G01X43307Y361811D02*
X13780D01*
G01X192914Y461024D02*
X3937D01*
G01X5906Y660433D02*
G03X9843Y656496I3937J0D01*
G01X5906Y727559D02*
Y660433D01*
G01X69488Y656496D02*
X9843D01*
G01X13780Y685335D02*
Y664370D01*
G01X69488D02*
X13780D01*
G01Y685335D02*
G03X5906I-3937J0D01*
G01Y710532D02*
G03X13780I3937J0D01*
G01Y729528D02*
Y710532D01*
G01X15748Y731496D02*
G03X13780Y729528I0J-1968D01*
G01X44819Y731496D02*
X15748D01*
G01X43307Y361811D02*
G03Y369685I0J3937D01*
G01X46675Y730184D02*
G03X44819Y731496I-1856J-657D01*
G01X46675Y730184D02*
G03X54098I3712J1313D01*
G01X53150Y181697D02*
G03X55118Y179729I1968J0D01*
G01X53150Y195477D02*
Y181697D01*
G01X55118Y179729D02*
X161418D01*
G01X55118Y197445D02*
G03X53150Y195477I0J-1968D01*
G01X161418Y197445D02*
X55118D01*
G01X73426Y282874D02*
G03X69488Y286811I-3937J0D01*
G01X81300Y282874D02*
G03X69488Y294685I-11811J0D01*
G01X74016Y369685D02*
G03Y361811I0J-3937D01*
G01X53150Y551382D02*
G03X55118Y549414I1968J0D01*
G01X53150Y565162D02*
Y551382D01*
G01X55118Y549414D02*
X161418D01*
G01X55118Y567130D02*
G03X53150Y565162I0J-1968D01*
G01X161418Y567130D02*
X55118D01*
G01X73426Y652559D02*
G03X69488Y656496I-3937J0D01*
G01X81300Y652559D02*
G03X69488Y664370I-11811J0D01*
G01X55954Y731496D02*
G03X54098Y730184I0J-1969D01*
G01X153544Y731496D02*
X55954D01*
G01X80709Y43307D02*
G03X82677Y41339I1968J0D01*
G01Y47244D02*
G03X80709Y45276I0J-1968D01*
G01X188977Y47244D02*
X82677D01*
G01Y41339D02*
X188977D01*
G01X80709Y45276D02*
Y43307D01*
G01X86614Y101181D02*
G03X82677Y105118I-3937J0D01*
G01X86614Y95276D02*
Y101181D01*
G01X82677Y91339D02*
G03X86614Y95276I0J3937D01*
G01X73426Y267323D02*
G03X77363Y263386I3937J0D01*
G01X73426Y267323D02*
Y282874D01*
G01X77363Y263386D02*
X159449D01*
G01X81300Y271260D02*
Y282874D01*
G01Y271260D02*
X155512D01*
G01Y361811D02*
X74016D01*
G01X80709Y412992D02*
G03X82677Y411024I1968J0D01*
G01Y416929D02*
G03X80709Y414961I0J-1968D01*
G01X188977Y416929D02*
X82677D01*
G01Y411024D02*
X188977D01*
G01X80709Y414961D02*
Y412992D01*
G01X86614Y464961D02*
Y470866D01*
G01X82677Y461024D02*
G03X86614Y464961I0J3937D01*
G01Y470866D02*
G03X82677Y474803I-3937J0D01*
G01X73426Y637008D02*
G03X77363Y633071I3937J0D01*
G01X73426Y637008D02*
Y652559D01*
G01X77363Y633071D02*
X159449D01*
G01X81300Y640945D02*
Y652559D01*
G01Y640945D02*
X155512D01*
G01X109449Y95276D02*
Y101181D01*
G01X113386Y105118D02*
G03X109449Y101181I0J-3937D01*
G01Y95276D02*
G03X113386Y91339I3937J0D01*
G01X109449Y464961D02*
Y470866D01*
G01Y464961D02*
G03X113386Y461024I3937J0D01*
G01Y474803D02*
G03X109449Y470866I0J-3937D01*
G01X161418Y179729D02*
G03X163386Y181697I0J1968D01*
G01Y195477D02*
G03X161418Y197445I-1968J0D01*
G01X159449Y263386D02*
G03X163386Y267323I0J3937D01*
G01X155512Y303937D02*
Y271260D01*
G01X163386Y303937D02*
G03X155512I-3937J0D01*
G01Y329134D02*
G03X163386I3937J0D01*
G01X155512Y361811D02*
Y329134D01*
G01X161418Y549414D02*
G03X163386Y551382I0J1968D01*
G01Y565162D02*
G03X161418Y567130I-1968J0D01*
G01X159449Y633071D02*
G03X163386Y637008I0J3937D01*
G01X155512Y673622D02*
Y640945D01*
G01X163386Y673622D02*
G03X155512I-3937J0D01*
G01Y698819D02*
G03X163386I3937J0D01*
G01X155512Y729528D02*
Y698819D01*
G01Y729528D02*
G03X153544Y731496I-1968J0D01*
G01X163386Y181697D02*
Y195477D01*
G01Y357874D02*
Y267323D01*
G01X167323Y361811D02*
G03X163386Y357874I0J-3937D01*
G01X535433Y361811D02*
X167323D01*
G01X163386Y551382D02*
Y565162D01*
G01Y727559D02*
Y637008D01*
G01X167323Y731496D02*
G03X163386Y727559I0J-3937D01*
G01X535433Y731496D02*
X167323D01*
G01X188977Y41339D02*
G03X190945Y43307I0J1968D01*
G01Y45276D02*
G03X188977Y47244I-1968J0D01*
G01X190945Y43307D02*
Y45276D01*
G01X196851Y97244D02*
G03X194882Y95276I0J-1969D01*
G01X192914Y91339D02*
G03X194882Y93307I0J1968D01*
G01X196851Y97244D02*
X269685D01*
G01X194882Y93307D02*
Y95276D01*
G01X188977Y411024D02*
G03X190945Y412992I0J1968D01*
G01Y414961D02*
G03X188977Y416929I-1968J0D01*
G01X190945Y412992D02*
Y414961D01*
G01X196851Y466929D02*
G03X194882Y464961I-1J-1968D01*
G01X192914Y461024D02*
G03X194882Y462992I0J1968D01*
G01D02*
Y464961D01*
G01X196851Y466929D02*
X269685D01*
G01Y97244D02*
G03X273622Y101181I0J3937D01*
G01Y252756D02*
Y101181D01*
G01X261811Y105118D02*
G03X265748Y109055I0J3937D01*
G01D02*
Y260630D01*
G01X273622Y165551D02*
G03X265748I-3937J0D01*
G01Y196260D02*
G03X273622I3937J0D01*
G01X269685Y264567D02*
G03X265748Y260630I0J-3937D01*
G01X277559Y256693D02*
G03X273622Y252756I0J-3937D01*
G01X342520Y264567D02*
X269685D01*
G01X254331Y361811D02*
G03Y369685I0J3937D01*
G01X261811Y474803D02*
G03X265748Y478740I0J3937D01*
G01D02*
Y630315D01*
G01X269685Y466929D02*
G03X273622Y470866I0J3937D01*
G01Y622441D02*
Y470866D01*
G01Y535236D02*
G03X265748I-3937J0D01*
G01Y565945D02*
G03X273622I3937J0D01*
G01X277559Y626378D02*
G03X273622Y622441I0J-3937D01*
G01X269685Y634252D02*
G03X265748Y630315I0J-3937D01*
G01X342520Y634252D02*
X269685D01*
G01X561024Y256693D02*
X277559D01*
G01X285040Y369685D02*
G03Y361811I0J-3937D01*
G01X561024Y626378D02*
X277559D01*
G01X342520Y264567D02*
G03X344488Y266536I0J1968D01*
G01X342520Y634252D02*
G03X344488Y636221I0J1968D01*
G01X346457Y270473D02*
G03X344488Y268504I0J-1969D01*
G01X346457Y270473D02*
X535433D01*
G01X344488Y268504D02*
Y266536D01*
G01X350394Y320473D02*
G03X348426Y318504I0J-1968D01*
G01Y316536D02*
G03X350394Y314567I1968J-1D01*
G01D02*
X456693D01*
G01Y320473D02*
X350394D01*
G01X348426Y318504D02*
Y316536D01*
G01X346457Y640158D02*
G03X344488Y638189I0J-1969D01*
G01X346457Y640158D02*
X535433D01*
G01X344488Y638189D02*
Y636221D01*
G01X350394Y690158D02*
G03X348426Y688189I0J-1968D01*
G01Y686221D02*
G03X350394Y684252I1968J-1D01*
G01D02*
X456693D01*
G01Y690158D02*
X350394D01*
G01X348426Y688189D02*
Y686221D01*
G01X383859Y1969D02*
G03X385827Y0I1968J-1D01*
G01D02*
X523622D01*
G01X372048D02*
G03X375985Y3937I0J3937D01*
G01X383859Y1969D02*
Y32677D01*
G01X375985Y3937D02*
Y94488D01*
G01X383859Y32677D02*
G03X375985I-3937J0D01*
G01Y57874D02*
G03X383859I3937J0D01*
G01D02*
Y90551D01*
G01X379922Y98425D02*
G03X375985Y94488I0J-3937D01*
G01X458071Y90551D02*
X383859D01*
G01X462008Y98425D02*
X379922D01*
G01X375985Y166334D02*
G03X377953Y164365I1969J0D01*
G01X375985Y180113D02*
Y166334D01*
G01X377953Y164365D02*
X484252D01*
G01X377953Y182082D02*
G03X375985Y180113I0J-1968D01*
G01X484252Y182082D02*
X377953D01*
G01X383859Y369685D02*
X465355D01*
G01X372048D02*
G03X375985Y373622I0J3937D01*
G01X383859Y369685D02*
Y402362D01*
G01X375985Y373622D02*
Y464173D01*
G01X383859Y402362D02*
G03X375985I-3937J0D01*
G01Y427559D02*
G03X383859I3937J0D01*
G01D02*
Y460236D01*
G01X379922Y468110D02*
G03X375985Y464173I0J-3937D01*
G01X458071Y460236D02*
X383859D01*
G01X462008Y468110D02*
X379922D01*
G01X375985Y536019D02*
G03X377953Y534050I1969J0D01*
G01D02*
X484252D01*
G01X377953Y551767D02*
G03X375985Y549799I0J-1968D01*
G01D02*
Y536019D01*
G01X484252Y551767D02*
X377953D01*
G01X429922Y260630D02*
Y266536D01*
G01X425985Y256693D02*
G03X429922Y260630I0J3937D01*
G01Y266536D02*
G03X425985Y270473I-3937J0D01*
G01X429922Y630315D02*
Y636221D01*
G01X425985Y626378D02*
G03X429922Y630315I0J3937D01*
G01Y636221D02*
G03X425985Y640158I-3937J0D01*
G01X452756Y260630D02*
G03X456693Y256693I3937J0D01*
G01X452756Y260630D02*
Y266536D01*
G01X456693Y270473D02*
G03X452756Y266536I0J-3937D01*
G01X458662Y318504D02*
G03X456693Y320473I-1969J0D01*
G01Y314567D02*
G03X458662Y316536I0J1969D01*
G01X452756Y630315D02*
G03X456693Y626378I3937J0D01*
G01X452756Y630315D02*
Y636221D01*
G01X456693Y640158D02*
G03X452756Y636221I0J-3937D01*
G01X458662Y688189D02*
G03X456693Y690158I-1969J0D01*
G01Y684252D02*
G03X458662Y686221I0J1969D01*
G01X458071Y78937D02*
G03X469882Y67126I11811J0D01*
G01X465945Y78937D02*
G03X469882Y75000I3937J0D01*
G01X458071Y90551D02*
Y78937D01*
G01X465945Y94488D02*
Y78937D01*
G01X469882Y67126D02*
X525591D01*
G01X469882Y75000D02*
X529528D01*
G01X465945Y94488D02*
G03X462008Y98425I-3937J0D01*
G01X458662Y316536D02*
Y318504D01*
G01X465355Y361811D02*
G03Y369685I0J3937D01*
G01X458071Y448622D02*
G03X469882Y436811I11811J0D01*
G01D02*
X525591D01*
G01X465945Y448622D02*
G03X469882Y444685I3937J0D01*
G01X465945Y464173D02*
G03X462008Y468110I-3937J0D01*
G01X458071Y460236D02*
Y448622D01*
G01X465945Y464173D02*
Y448622D01*
G01X469882Y444685D02*
X529528D01*
G01X458662Y686221D02*
Y688189D01*
G01X484252Y164365D02*
G03X486221Y166334I0J1969D01*
G01D02*
Y180113D01*
G01D02*
G03X484252Y182082I-1969J0D01*
G01X496063Y369685D02*
G03Y361811I0J-3937D01*
G01Y369685D02*
X525591D01*
G01X484252Y534050D02*
G03X486221Y536019I0J1969D01*
G01Y549799D02*
G03X484252Y551767I-1969J-1D01*
G01X486221Y536019D02*
Y549799D01*
G01X523622Y0D02*
G03X525591Y1969I0J1969D01*
G01X533465Y3937D02*
G03X537402Y0I3937J0D01*
G01X525591Y1969D02*
Y20965D01*
G01X533465Y3937D02*
Y71063D01*
G01X537402Y0D02*
X561024D01*
G01X533465Y20965D02*
G03X525591I-3937J0D01*
G01Y46162D02*
G03X533465I3937J0D01*
G01X525591D02*
Y67126D01*
G01X533465Y71063D02*
G03X529528Y75000I-3937J0D01*
G01X535433Y270473D02*
G03X539370Y274410I0J3937D01*
G01D02*
Y357874D01*
G01X547244Y270473D02*
X562992D01*
G01X547244D02*
Y303543D01*
G01D02*
G03X539370I-3937J0D01*
G01Y328740D02*
G03X547244I3937J0D01*
G01D02*
Y361811D01*
G01X539370Y357874D02*
G03X535433Y361811I-3937J0D01*
G01X547244D02*
X562992D01*
G01X533465Y373622D02*
G03X537402Y369685I3937J0D01*
G01X525591D02*
Y390650D01*
G01X533465Y373622D02*
Y440748D01*
G01X537402Y369685D02*
X561024D01*
G01X533465Y390650D02*
G03X525591I-3937J0D01*
G01Y415847D02*
G03X533465I3937J0D01*
G01X525591D02*
Y436811D01*
G01X533465Y440748D02*
G03X529528Y444685I-3937J0D01*
G01X535433Y640158D02*
G03X539370Y644095I0J3937D01*
G01D02*
Y727559D01*
G01X547244Y640158D02*
X562992D01*
G01X547244D02*
Y673228D01*
G01D02*
G03X539370I-3937J0D01*
G01Y698425D02*
G03X547244I3937J0D01*
G01D02*
Y727559D01*
G01X551181Y731496D02*
G03X547244Y727559I0J-3937D01*
G01X539370D02*
G03X535433Y731496I-3937J0D01*
G01X561024Y0D02*
G03X564961Y3937I0J3937D01*
G01D02*
Y252756D01*
G01D02*
G03X561024Y256693I-3937J0D01*
G01X562992Y270473D02*
G03X564961Y272441I1J1968D01*
G01D02*
Y359843D01*
G01D02*
G03X562992Y361811I-1968J0D01*
G01X561024Y369685D02*
G03X564961Y373622I0J3937D01*
G01D02*
Y622441D01*
G01D02*
G03X561024Y626378I-3937J0D01*
G01X562992Y640158D02*
G03X564961Y642126I1J1968D01*
G01D02*
Y721654D01*
G01D02*
G03X555118Y731496I-9842J0D01*
G01X551181D02*
X555118D01*
M02*
